(kicad_pcb
	(version 20260206)
	(generator "pcbnew")
	(generator_version "10.0")
	(general
		(thickness 1.6)
		(legacy_teardrops no)
	)
	(paper "A4")
	(title_block
		(title "pdpb — Lightning_PDPB_BRD.brd")
		(comment 1 "Lightning (Wiwynn / Facebook NVMe JBOF) / footprints 952-959 of 1140")
	)
	(layers
		(0 "F.Cu" signal "TOP")
		(4 "In1.Cu" signal "L2GND")
		(6 "In2.Cu" signal "L3")
		(8 "In3.Cu" signal "L4VCC")
		(10 "In4.Cu" signal "L5VCC")
		(12 "In5.Cu" signal "L6")
		(14 "In6.Cu" signal "L7GND")
		(2 "B.Cu" signal "BOTTOM")
		(9 "F.Adhes" user "F.Adhesive")
		(11 "B.Adhes" user "B.Adhesive")
		(13 "F.Paste" user "Package Geometry/Pastemask Top")
		(15 "B.Paste" user "Package Geometry/Pastemask Bottom")
		(5 "F.SilkS" user "Ref Des/Silkscreen Top")
		(7 "B.SilkS" user "Ref Des/Silkscreen Bottom")
		(1 "F.Mask" user "Board Geometry/Soldermask Top")
		(3 "B.Mask" user "Board Geometry/Soldermask Bottom")
		(17 "Dwgs.User" user "User.Drawings")
		(19 "Cmts.User" user "User.Comments")
		(21 "Eco1.User" user "User.Eco1")
		(23 "Eco2.User" user "User.Eco2")
		(25 "Edge.Cuts" user "Board Geometry/Outline")
		(27 "Margin" user)
		(31 "F.CrtYd" user "Package Geometry/Place Bound Top")
		(29 "B.CrtYd" user "Package Geometry/Place Bound Bottom")
		(35 "F.Fab" user "Ref Des/Assembly Top")
		(33 "B.Fab" user "Ref Des/Assembly Bottom")
	)
	(footprint ""
		(layer "F.Cu")
		(at 24.9936 -317.0936 180)
		(property "Reference" "PC1223"
			(at 0 0 180)
			(layer "F.SilkS")
			(hide yes)
			(effects
				(font
					(size 1.27 1.27)
				)
			)
		)
		(property "Value" "SCD01U50V2KX-1GP"
			(at 1.1811 -2.7051 180)
			(unlocked yes)
			(layer "F.Fab")
			(hide yes)
			(effects
				(font
					(size 1.016 1.016)
					(thickness 0.1524)
				)
			)
		)
		(property "Device Type" "C402H22"
			(at 1.1811 -4.2291 180)
			(unlocked yes)
			(layer "F.Fab")
			(hide yes)
			(effects
				(font
					(size 1.016 1.016)
					(thickness 0.1524)
				)
			)
		)
		(duplicate_pad_numbers_are_jumpers no)
		(fp_rect
			(start -0.4318 0.9525)
			(end 0.4318 -0.9525)
			(stroke
				(width 0)
				(type default)
			)
			(fill no)
			(layer "F.CrtYd")
		)
		(fp_rect
			(start -0.4318 0.9525)
			(end 0.4318 -0.9525)
			(stroke
				(width 0)
				(type default)
			)
			(fill no)
			(layer "F.Fab")
		)
		(pad "1" smd custom
			(at 0 -0.4445 180)
			(size 0.1524 0.1524)
			(layers "F.Cu" "F.Mask" "F.Paste")
			(net "P12V_SSD11")
			(options
				(clearance outline)
				(anchor circle)
			)
			(primitives
				(gr_poly
					(pts
						(arc
							(start 0.3048 -0.2032)
							(mid 0.275042 -0.275042)
							(end 0.2032 -0.3048)
						)
						(arc
							(start -0.2032 -0.3048)
							(mid -0.275042 -0.275042)
							(end -0.3048 -0.2032)
						)
						(arc
							(start -0.3048 0.2032)
							(mid -0.275042 0.275042)
							(end -0.2032 0.3048)
						)
						(arc
							(start 0.2032 0.3048)
							(mid 0.275042 0.275042)
							(end 0.3048 0.2032)
						)
					)
					(width 0)
					(fill yes)
				)
			)
		)
		(pad "2" smd custom
			(at 0 0.4445 180)
			(size 0.1524 0.1524)
			(layers "F.Cu" "F.Mask" "F.Paste")
			(net "GND")
			(options
				(clearance outline)
				(anchor circle)
			)
			(primitives
				(gr_poly
					(pts
						(arc
							(start 0.3048 -0.2032)
							(mid 0.275042 -0.275042)
							(end 0.2032 -0.3048)
						)
						(arc
							(start -0.2032 -0.3048)
							(mid -0.275042 -0.275042)
							(end -0.3048 -0.2032)
						)
						(arc
							(start -0.3048 0.2032)
							(mid -0.275042 0.275042)
							(end -0.2032 0.3048)
						)
						(arc
							(start 0.2032 0.3048)
							(mid 0.275042 0.275042)
							(end 0.3048 0.2032)
						)
					)
					(width 0)
					(fill yes)
				)
			)
		)
	)
	(footprint ""
		(layer "F.Cu")
		(at 245.491 -421.894 -90)
		(property "Reference" "C355"
			(at 0 0 270)
			(layer "F.SilkS")
			(hide yes)
			(effects
				(font
					(size 1.27 1.27)
				)
			)
		)
		(property "Value" "SC220P50V3JN-GP"
			(at 0 -2.8194 270)
			(unlocked yes)
			(layer "F.Fab")
			(hide yes)
			(effects
				(font
					(size 1.016 1.016)
					(thickness 0.1524)
				)
			)
		)
		(property "Device Type" "C603H36"
			(at 0 -4.3434 270)
			(unlocked yes)
			(layer "F.Fab")
			(hide yes)
			(effects
				(font
					(size 1.016 1.016)
					(thickness 0.1524)
				)
			)
		)
		(duplicate_pad_numbers_are_jumpers no)
		(fp_line
			(start 0.508 0)
			(end -0.508 0)
			(stroke
				(width 0.2032)
				(type default)
			)
			(layer "F.SilkS")
		)
		(fp_rect
			(start -0.5842 1.3335)
			(end 0.5842 -1.3335)
			(stroke
				(width 0)
				(type default)
			)
			(fill no)
			(layer "F.CrtYd")
		)
		(fp_rect
			(start -0.5842 1.3335)
			(end 0.5842 -1.3335)
			(stroke
				(width 0)
				(type default)
			)
			(fill no)
			(layer "F.Fab")
		)
		(pad "1" smd custom
			(at 0 -0.762 270)
			(size 0.2159 0.2159)
			(layers "F.Cu" "F.Mask" "F.Paste")
			(net "I2C_C_SDA")
			(options
				(clearance outline)
				(anchor circle)
			)
			(primitives
				(gr_poly
					(pts
						(arc
							(start -0.3302 -0.4318)
							(mid -0.402042 -0.402042)
							(end -0.4318 -0.3302)
						)
						(arc
							(start -0.4318 0.3302)
							(mid -0.402042 0.402042)
							(end -0.3302 0.4318)
						)
						(arc
							(start 0.3302 0.4318)
							(mid 0.402042 0.402042)
							(end 0.4318 0.3302)
						)
						(arc
							(start 0.4318 -0.3302)
							(mid 0.402042 -0.402042)
							(end 0.3302 -0.4318)
						)
					)
					(width 0)
					(fill yes)
				)
			)
		)
		(pad "2" smd custom
			(at 0 0.762 270)
			(size 0.2159 0.2159)
			(layers "F.Cu" "F.Mask" "F.Paste")
			(net "GND")
			(options
				(clearance outline)
				(anchor circle)
			)
			(primitives
				(gr_poly
					(pts
						(arc
							(start -0.3302 -0.4318)
							(mid -0.402042 -0.402042)
							(end -0.4318 -0.3302)
						)
						(arc
							(start -0.4318 0.3302)
							(mid -0.402042 0.402042)
							(end -0.3302 0.4318)
						)
						(arc
							(start 0.3302 0.4318)
							(mid 0.402042 0.402042)
							(end 0.4318 0.3302)
						)
						(arc
							(start 0.4318 -0.3302)
							(mid 0.402042 -0.402042)
							(end 0.3302 -0.4318)
						)
					)
					(width 0)
					(fill yes)
				)
			)
		)
	)
	(footprint ""
		(layer "F.Cu")
		(at 87.503 -432.943 180)
		(property "Reference" "C8896"
			(at 0 0 180)
			(layer "F.SilkS")
			(hide yes)
			(effects
				(font
					(size 1.27 1.27)
				)
			)
		)
		(property "Value" "SCD1U16V2KX-3GP"
			(at 1.1811 -2.7051 180)
			(unlocked yes)
			(layer "F.Fab")
			(hide yes)
			(effects
				(font
					(size 1.016 1.016)
					(thickness 0.1524)
				)
			)
		)
		(property "Device Type" "C402H22"
			(at 1.1811 -4.2291 180)
			(unlocked yes)
			(layer "F.Fab")
			(hide yes)
			(effects
				(font
					(size 1.016 1.016)
					(thickness 0.1524)
				)
			)
		)
		(duplicate_pad_numbers_are_jumpers no)
		(fp_rect
			(start -0.4318 0.9525)
			(end 0.4318 -0.9525)
			(stroke
				(width 0)
				(type default)
			)
			(fill no)
			(layer "F.CrtYd")
		)
		(fp_rect
			(start -0.4318 0.9525)
			(end 0.4318 -0.9525)
			(stroke
				(width 0)
				(type default)
			)
			(fill no)
			(layer "F.Fab")
		)
		(pad "1" smd custom
			(at 0 -0.4445 180)
			(size 0.1524 0.1524)
			(layers "F.Cu" "F.Mask" "F.Paste")
			(net "VDDR_1")
			(options
				(clearance outline)
				(anchor circle)
			)
			(primitives
				(gr_poly
					(pts
						(arc
							(start 0.3048 -0.2032)
							(mid 0.275042 -0.275042)
							(end 0.2032 -0.3048)
						)
						(arc
							(start -0.2032 -0.3048)
							(mid -0.275042 -0.275042)
							(end -0.3048 -0.2032)
						)
						(arc
							(start -0.3048 0.2032)
							(mid -0.275042 0.275042)
							(end -0.2032 0.3048)
						)
						(arc
							(start 0.2032 0.3048)
							(mid 0.275042 0.275042)
							(end 0.3048 0.2032)
						)
					)
					(width 0)
					(fill yes)
				)
			)
		)
		(pad "2" smd custom
			(at 0 0.4445 180)
			(size 0.1524 0.1524)
			(layers "F.Cu" "F.Mask" "F.Paste")
			(net "GND")
			(options
				(clearance outline)
				(anchor circle)
			)
			(primitives
				(gr_poly
					(pts
						(arc
							(start 0.3048 -0.2032)
							(mid 0.275042 -0.275042)
							(end 0.2032 -0.3048)
						)
						(arc
							(start -0.2032 -0.3048)
							(mid -0.275042 -0.275042)
							(end -0.3048 -0.2032)
						)
						(arc
							(start -0.3048 0.2032)
							(mid -0.275042 0.275042)
							(end -0.2032 0.3048)
						)
						(arc
							(start 0.2032 0.3048)
							(mid 0.275042 0.275042)
							(end 0.3048 0.2032)
						)
					)
					(width 0)
					(fill yes)
				)
			)
		)
	)
	(footprint ""
		(layer "F.Cu")
		(at 208.026 -454.66)
		(property "Reference" "R325"
			(at 0 0 0)
			(layer "F.SilkS")
			(hide yes)
			(effects
				(font
					(size 1.27 1.27)
				)
			)
		)
		(property "Value" "4K7R2J-2-GP"
			(at 0.064008 -3.993896 0)
			(unlocked yes)
			(layer "F.Fab")
			(hide yes)
			(effects
				(font
					(size 1.016 1.016)
					(thickness 0.1524)
				)
			)
		)
		(property "Device Type" "R402H16"
			(at 0.064008 -5.517896 0)
			(unlocked yes)
			(layer "F.Fab")
			(hide yes)
			(effects
				(font
					(size 1.016 1.016)
					(thickness 0.1524)
				)
			)
		)
		(duplicate_pad_numbers_are_jumpers no)
		(fp_line
			(start -0.508 -0.9398)
			(end -0.508 0.9398)
			(stroke
				(width 0.1524)
				(type default)
			)
			(layer "F.SilkS")
		)
		(fp_line
			(start 0.508 -0.9398)
			(end -0.508 -0.9398)
			(stroke
				(width 0.1524)
				(type default)
			)
			(layer "F.SilkS")
		)
		(fp_rect
			(start -0.508 0.9398)
			(end 0.508 -0.9398)
			(stroke
				(width 0)
				(type default)
			)
			(fill no)
			(layer "F.CrtYd")
		)
		(fp_rect
			(start -0.508 0.9398)
			(end 0.508 -0.9398)
			(stroke
				(width 0)
				(type default)
			)
			(fill no)
			(layer "F.Fab")
		)
		(pad "1" smd custom
			(at 0 -0.4445)
			(size 0.1397 0.1397)
			(layers "F.Cu" "F.Mask" "F.Paste")
			(net "I2C_B_TMP2_A0")
			(options
				(clearance outline)
				(anchor circle)
			)
			(primitives
				(gr_poly
					(pts
						(arc
							(start -0.1778 -0.2794)
							(mid -0.249642 -0.249642)
							(end -0.2794 -0.1778)
						)
						(arc
							(start -0.2794 0.1778)
							(mid -0.249642 0.249642)
							(end -0.1778 0.2794)
						)
						(arc
							(start 0.1778 0.2794)
							(mid 0.249642 0.249642)
							(end 0.2794 0.1778)
						)
						(arc
							(start 0.2794 -0.1778)
							(mid 0.249642 -0.249642)
							(end 0.1778 -0.2794)
						)
					)
					(width 0)
					(fill yes)
				)
			)
		)
		(pad "2" smd custom
			(at 0 0.4445)
			(size 0.1397 0.1397)
			(layers "F.Cu" "F.Mask" "F.Paste")
			(net "GND")
			(options
				(clearance outline)
				(anchor circle)
			)
			(primitives
				(gr_poly
					(pts
						(arc
							(start -0.1778 -0.2794)
							(mid -0.249642 -0.249642)
							(end -0.2794 -0.1778)
						)
						(arc
							(start -0.2794 0.1778)
							(mid -0.249642 0.249642)
							(end -0.1778 0.2794)
						)
						(arc
							(start 0.1778 0.2794)
							(mid 0.249642 0.249642)
							(end 0.2794 0.1778)
						)
						(arc
							(start 0.2794 -0.1778)
							(mid 0.249642 -0.249642)
							(end 0.1778 -0.2794)
						)
					)
					(width 0)
					(fill yes)
				)
			)
		)
	)
	(footprint ""
		(layer "F.Cu")
		(at 89.789 -320.167 90)
		(property "Reference" "R9437"
			(at 0 0 90)
			(layer "F.SilkS")
			(hide yes)
			(effects
				(font
					(size 1.27 1.27)
				)
			)
		)
		(property "Value" "4K7R2J-2-GP"
			(at 0.064008 -3.993896 90)
			(unlocked yes)
			(layer "F.Fab")
			(hide yes)
			(effects
				(font
					(size 1.016 1.016)
					(thickness 0.1524)
				)
			)
		)
		(property "Device Type" "R402H16"
			(at 0.064008 -5.517896 90)
			(unlocked yes)
			(layer "F.Fab")
			(hide yes)
			(effects
				(font
					(size 1.016 1.016)
					(thickness 0.1524)
				)
			)
		)
		(duplicate_pad_numbers_are_jumpers no)
		(fp_line
			(start 0.508 -0.9398)
			(end -0.508 -0.9398)
			(stroke
				(width 0.1524)
				(type default)
			)
			(layer "F.SilkS")
		)
		(fp_line
			(start -0.508 -0.9398)
			(end -0.508 0.9398)
			(stroke
				(width 0.1524)
				(type default)
			)
			(layer "F.SilkS")
		)
		(fp_rect
			(start -0.508 0.9398)
			(end 0.508 -0.9398)
			(stroke
				(width 0)
				(type default)
			)
			(fill no)
			(layer "F.CrtYd")
		)
		(fp_rect
			(start -0.508 0.9398)
			(end 0.508 -0.9398)
			(stroke
				(width 0)
				(type default)
			)
			(fill no)
			(layer "F.Fab")
		)
		(pad "1" smd custom
			(at 0 -0.4445 90)
			(size 0.1397 0.1397)
			(layers "F.Cu" "F.Mask" "F.Paste")
			(net "P3V3")
			(options
				(clearance outline)
				(anchor circle)
			)
			(primitives
				(gr_poly
					(pts
						(arc
							(start -0.1778 -0.2794)
							(mid -0.249642 -0.249642)
							(end -0.2794 -0.1778)
						)
						(arc
							(start -0.2794 0.1778)
							(mid -0.249642 0.249642)
							(end -0.1778 0.2794)
						)
						(arc
							(start 0.1778 0.2794)
							(mid 0.249642 0.249642)
							(end 0.2794 0.1778)
						)
						(arc
							(start 0.2794 -0.1778)
							(mid 0.249642 -0.249642)
							(end 0.1778 -0.2794)
						)
					)
					(width 0)
					(fill yes)
				)
			)
		)
		(pad "2" smd custom
			(at 0 0.4445 90)
			(size 0.1397 0.1397)
			(layers "F.Cu" "F.Mask" "F.Paste")
			(net "SSD_PRSNT_NET11")
			(options
				(clearance outline)
				(anchor circle)
			)
			(primitives
				(gr_poly
					(pts
						(arc
							(start -0.1778 -0.2794)
							(mid -0.249642 -0.249642)
							(end -0.2794 -0.1778)
						)
						(arc
							(start -0.2794 0.1778)
							(mid -0.249642 0.249642)
							(end -0.1778 0.2794)
						)
						(arc
							(start 0.1778 0.2794)
							(mid 0.249642 0.249642)
							(end 0.2794 0.1778)
						)
						(arc
							(start 0.2794 -0.1778)
							(mid 0.249642 -0.249642)
							(end 0.1778 -0.2794)
						)
					)
					(width 0)
					(fill yes)
				)
			)
		)
	)
	(footprint ""
		(layer "F.Cu")
		(at 97.028 -86.614 -90)
		(property "Reference" "R9458"
			(at 0 0 270)
			(layer "F.SilkS")
			(hide yes)
			(effects
				(font
					(size 1.27 1.27)
				)
			)
		)
		(property "Value" "4K7R2J-2-GP"
			(at 0.064008 -3.993896 270)
			(unlocked yes)
			(layer "F.Fab")
			(hide yes)
			(effects
				(font
					(size 1.016 1.016)
					(thickness 0.1524)
				)
			)
		)
		(property "Device Type" "R402H16"
			(at 0.064008 -5.517896 270)
			(unlocked yes)
			(layer "F.Fab")
			(hide yes)
			(effects
				(font
					(size 1.016 1.016)
					(thickness 0.1524)
				)
			)
		)
		(duplicate_pad_numbers_are_jumpers no)
		(fp_line
			(start -0.508 -0.9398)
			(end -0.508 0.9398)
			(stroke
				(width 0.1524)
				(type default)
			)
			(layer "F.SilkS")
		)
		(fp_line
			(start 0.508 -0.9398)
			(end -0.508 -0.9398)
			(stroke
				(width 0.1524)
				(type default)
			)
			(layer "F.SilkS")
		)
		(fp_rect
			(start -0.508 0.9398)
			(end 0.508 -0.9398)
			(stroke
				(width 0)
				(type default)
			)
			(fill no)
			(layer "F.CrtYd")
		)
		(fp_rect
			(start -0.508 0.9398)
			(end 0.508 -0.9398)
			(stroke
				(width 0)
				(type default)
			)
			(fill no)
			(layer "F.Fab")
		)
		(pad "1" smd custom
			(at 0 -0.4445 270)
			(size 0.1397 0.1397)
			(layers "F.Cu" "F.Mask" "F.Paste")
			(net "P3V3")
			(options
				(clearance outline)
				(anchor circle)
			)
			(primitives
				(gr_poly
					(pts
						(arc
							(start -0.1778 -0.2794)
							(mid -0.249642 -0.249642)
							(end -0.2794 -0.1778)
						)
						(arc
							(start -0.2794 0.1778)
							(mid -0.249642 0.249642)
							(end -0.1778 0.2794)
						)
						(arc
							(start 0.1778 0.2794)
							(mid 0.249642 0.249642)
							(end 0.2794 0.1778)
						)
						(arc
							(start 0.2794 -0.1778)
							(mid 0.249642 -0.249642)
							(end 0.1778 -0.2794)
						)
					)
					(width 0)
					(fill yes)
				)
			)
		)
		(pad "2" smd custom
			(at 0 0.4445 270)
			(size 0.1397 0.1397)
			(layers "F.Cu" "F.Mask" "F.Paste")
			(net "SSD_PRSNT_NET14")
			(options
				(clearance outline)
				(anchor circle)
			)
			(primitives
				(gr_poly
					(pts
						(arc
							(start -0.1778 -0.2794)
							(mid -0.249642 -0.249642)
							(end -0.2794 -0.1778)
						)
						(arc
							(start -0.2794 0.1778)
							(mid -0.249642 0.249642)
							(end -0.1778 0.2794)
						)
						(arc
							(start 0.1778 0.2794)
							(mid 0.249642 0.249642)
							(end 0.2794 0.1778)
						)
						(arc
							(start 0.2794 -0.1778)
							(mid 0.249642 -0.249642)
							(end 0.1778 -0.2794)
						)
					)
					(width 0)
					(fill yes)
				)
			)
		)
	)
	(footprint ""
		(layer "F.Cu")
		(at 43.0022 -299.593)
		(property "Reference" "R9250"
			(at 0 0 0)
			(layer "F.SilkS")
			(hide yes)
			(effects
				(font
					(size 1.27 1.27)
				)
			)
		)
		(property "Value" "2R2010F-GP"
			(at 0.0762 -4.5466 0)
			(unlocked yes)
			(layer "F.Fab")
			(hide yes)
			(effects
				(font
					(size 1.016 1.016)
					(thickness 0.1524)
				)
			)
		)
		(property "Device Type" "R2010H26"
			(at 0.0762 -6.1468 0)
			(unlocked yes)
			(layer "F.Fab")
			(hide yes)
			(effects
				(font
					(size 1.016 1.016)
					(thickness 0.1524)
				)
			)
		)
		(duplicate_pad_numbers_are_jumpers no)
		(fp_line
			(start -3.302 -1.651)
			(end -3.302 1.651)
			(stroke
				(width 0.1524)
				(type default)
			)
			(layer "F.SilkS")
		)
		(fp_line
			(start -3.302 1.651)
			(end 3.302 1.651)
			(stroke
				(width 0.1524)
				(type default)
			)
			(layer "F.SilkS")
		)
		(fp_line
			(start 3.302 -1.651)
			(end -3.302 -1.651)
			(stroke
				(width 0.1524)
				(type default)
			)
			(layer "F.SilkS")
		)
		(fp_line
			(start 3.302 1.651)
			(end 3.302 -1.651)
			(stroke
				(width 0.1524)
				(type default)
			)
			(layer "F.SilkS")
		)
		(fp_rect
			(start -3.3782 1.7272)
			(end 3.3782 -1.7272)
			(stroke
				(width 0)
				(type default)
			)
			(fill no)
			(layer "F.CrtYd")
		)
		(fp_poly
			(pts
				(xy 3.3782 -1.7272) (xy -3.3782 -1.7272) (xy -3.3782 1.7272) (xy 3.3782 1.7272)
			)
			(stroke
				(width 0)
				(type default)
			)
			(fill no)
			(layer "F.Fab")
		)
		(pad "1" smd rect
			(at -2.3495 0)
			(size 1.143 2.794)
			(layers "F.Cu" "F.Mask" "F.Paste")
			(net "P12V_SSD7")
		)
		(pad "2" smd rect
			(at 2.3495 0)
			(size 1.143 2.794)
			(layers "F.Cu" "F.Mask" "F.Paste")
			(net "12V_PRECH_SSD7")
		)
	)
	(footprint ""
		(layer "F.Cu")
		(at 33.274 -13.6652 180)
		(property "Reference" "PC1232"
			(at 0 0 180)
			(layer "F.SilkS")
			(hide yes)
			(effects
				(font
					(size 1.27 1.27)
				)
			)
		)
		(property "Value" "SCD1U50V3KX-GP"
			(at 0 -2.8194 180)
			(unlocked yes)
			(layer "F.Fab")
			(hide yes)
			(effects
				(font
					(size 1.016 1.016)
					(thickness 0.1524)
				)
			)
		)
		(property "Device Type" "C603H36"
			(at 0 -4.3434 180)
			(unlocked yes)
			(layer "F.Fab")
			(hide yes)
			(effects
				(font
					(size 1.016 1.016)
					(thickness 0.1524)
				)
			)
		)
		(duplicate_pad_numbers_are_jumpers no)
		(fp_line
			(start 0.508 0)
			(end -0.508 0)
			(stroke
				(width 0.2032)
				(type default)
			)
			(layer "F.SilkS")
		)
		(fp_rect
			(start -0.5842 1.3335)
			(end 0.5842 -1.3335)
			(stroke
				(width 0)
				(type default)
			)
			(fill no)
			(layer "F.CrtYd")
		)
		(fp_rect
			(start -0.5842 1.3335)
			(end 0.5842 -1.3335)
			(stroke
				(width 0)
				(type default)
			)
			(fill no)
			(layer "F.Fab")
		)
		(pad "1" smd custom
			(at 0 -0.762 180)
			(size 0.2159 0.2159)
			(layers "F.Cu" "F.Mask" "F.Paste")
			(net "P12V_SSD14")
			(options
				(clearance outline)
				(anchor circle)
			)
			(primitives
				(gr_poly
					(pts
						(arc
							(start -0.3302 -0.4318)
							(mid -0.402042 -0.402042)
							(end -0.4318 -0.3302)
						)
						(arc
							(start -0.4318 0.3302)
							(mid -0.402042 0.402042)
							(end -0.3302 0.4318)
						)
						(arc
							(start 0.3302 0.4318)
							(mid 0.402042 0.402042)
							(end 0.4318 0.3302)
						)
						(arc
							(start 0.4318 -0.3302)
							(mid 0.402042 -0.402042)
							(end 0.3302 -0.4318)
						)
					)
					(width 0)
					(fill yes)
				)
			)
		)
		(pad "2" smd custom
			(at 0 0.762 180)
			(size 0.2159 0.2159)
			(layers "F.Cu" "F.Mask" "F.Paste")
			(net "GND")
			(options
				(clearance outline)
				(anchor circle)
			)
			(primitives
				(gr_poly
					(pts
						(arc
							(start -0.3302 -0.4318)
							(mid -0.402042 -0.402042)
							(end -0.4318 -0.3302)
						)
						(arc
							(start -0.4318 0.3302)
							(mid -0.402042 0.402042)
							(end -0.3302 0.4318)
						)
						(arc
							(start 0.3302 0.4318)
							(mid 0.402042 0.402042)
							(end 0.4318 0.3302)
						)
						(arc
							(start 0.4318 -0.3302)
							(mid 0.402042 -0.402042)
							(end 0.3302 -0.4318)
						)
					)
					(width 0)
					(fill yes)
				)
			)
		)
	)
)
